FILE_TYPE = CONNECTIVITY;
{Allegro Design Entry HDL 16.6-p007 (v16-6-112F) 10/10/2012}
"PAGE_NUMBER" = 123;
0"NC";
1"GND\g";
2"GND\g";
3"PVNN_PCH_STBY\g";
4"PVNN_PCH_STBY\g";
5"P1V05_PCH_STBY\g";
6"VSENSE_PVNN_PCH_STBY_QAT";
7"VSENSE_PVNN_PCH_STBY_FPK";
%"LBG_CORE_QAT_EXT_D"
"11","(-1625,2575)","0","mstr_u_proc","I13";
;
CDS_SEC"11"
LOCATION"U7C1"
PART_NUMBER"H91415-002"
MATERIAL"IC"
PACK_TYPE"BGA1"
SEC_TYPE"BGA1"
SEC"11"
CDS_LIB"mstr_u_proc"
BOM_COST"SB"
CDS_LOCATION"U7C1"
ROOM"SB";
"VSS<494>"
$PN"BP69"2;
"VSS<493>"
$PN"BT69"2;
"VSS<492>"
$PN"BU70"2;
"VSS<491>"
$PN"BR70"2;
"VSS<490>"
$PN"F70"2;
"VSS<489>"
$PN"E70"2;
"VSS<488>"
$PN"BU3"2;
"VSS<487>"
$PN"BR3"2;
"VSS<486>"
$PN"F3"2;
"VSS<485>"
$PN"E3"2;
"VSS<484>"
$PN"A5"2;
"VSS<483>"
$PN"A7"2;
"VSS<482>"
$PN"A9"2;
"VSS<481>"
$PN"A65"2;
"VSS<480>"
$PN"A66"2;
"VSS<479>"
$PN"A68"2;
"VSS<478>"
$PN"J1"2;
"VSS<477>"
$PN"J72"2;
"VSS<476>"
$PN"BN1"2;
"VSS<475>"
$PN"BN72"2;
"VSS<474>"
$PN"CA68"2;
"VSS<473>"
$PN"CA66"2;
"VSS<472>"
$PN"CA65"2;
"VSS<471>"
$PN"CA9"2;
"VSS<470>"
$PN"CA7"2;
"VSS<469>"
$PN"CA5"2;
"VSS<468>"
$PN"A70"2;
"VSS<467>"
$PN"CA3"2;
"VSS<466>"
$PN"BW1"2;
"VSS<465>"
$PN"BU1"2;
"VSS<464>"
$PN"BR1"2;
"VSS<463>"
$PN"C3"2;
"VSS<462>"
$PN"C72"2;
"VSS<461>"
$PN"E1"2;
"VSS<460>"
$PN"E72"2;
"VSS<459>"
$PN"G1"2;
"VSS<458>"
$PN"G72"2;
"VSS<457>"
$PN"BR72"2;
"VSS<456>"
$PN"BU72"2;
"VSS<455>"
$PN"BW70"2;
"VSS<454>"
$PN"BW72"2;
"VSS<453>"
$PN"CA70"2;
"VSS<452>"
$PN"BB48"2;
"VSS<451>"
$PN"AT37"2;
"VSS<450>"
$PN"Y72"2;
"VSS<449>"
$PN"Y70"2;
"VSS<448>"
$PN"A18"2;
"VSS<447>"
$PN"A22"2;
"VSS<446>"
$PN"A30"2;
"VSS<445>"
$PN"A34"2;
"VSS<444>"
$PN"A37"2;
"VSS<443>"
$PN"A41"2;
"VSS<442>"
$PN"B12"2;
"VSS<441>"
$PN"B19"2;
"VSS<440>"
$PN"B25"2;
"VSS<439>"
$PN"B27"2;
"VSS<438>"
$PN"B47"2;
"VSS<437>"
$PN"C22"2;
"VSS<436>"
$PN"C30"2;
"VSS<435>"
$PN"C34"2;
"VSS<434>"
$PN"C37"2;
"VSS<433>"
$PN"C41"2;
"VSS<432>"
$PN"C65"2;
"VSS<431>"
$PN"D12"2;
"VSS<430>"
$PN"D16"2;
"VSS<429>"
$PN"D19"2;
"VSS<428>"
$PN"D25"2;
"VSS<427>"
$PN"D27"2;
"VSS<426>"
$PN"E59"2;
"VSS<425>"
$PN"E65"2;
"VSS<424>"
$PN"D47"1;
"VSS<423>"
$PN"E11"1;
"VSS<422>"
$PN"E13"1;
"VSS<421>"
$PN"E15"1;
"VSS<420>"
$PN"E20"1;
"VSS<419>"
$PN"E22"1;
"VSS<418>"
$PN"E24"1;
"VSS<417>"
$PN"E26"1;
"VSS<416>"
$PN"E28"1;
"VSS<415>"
$PN"E30"1;
"VSS<414>"
$PN"E32"1;
"VSS<413>"
$PN"E34"1;
"VSS<412>"
$PN"E37"1;
"VSS<411>"
$PN"E39"1;
"VSS<410>"
$PN"E41"1;
"VSS<409>"
$PN"E43"1;
"VSS<408>"
$PN"E45"1;
"VSS<407>"
$PN"E48"1;
"VSS<406>"
$PN"E50"1;
"VSS<405>"
$PN"E52"1;
"VSS<404>"
$PN"E54"1;
"VSS<403>"
$PN"E57"1;
"VSS<402>"
$PN"E6"1;
"VSS<401>"
$PN"E61"1;
"VSS<400>"
$PN"E63"1;
"VSS<399>"
$PN"G59"1;
"VSS<398>"
$PN"E9"1;
"VSS<397>"
$PN"G22"1;
"VSS<396>"
$PN"G29"1;
"VSS<395>"
$PN"G37"1;
"VSS<394>"
$PN"G48"1;
"VSS<393>"
$PN"G6"1;
"VSS<392>"
$PN"G63"1;
"VSS<391>"
$PN"G66"1;
"VSS<390>"
$PN"H58"1;
"VSS<389>"
$PN"J29"1;
"VSS<388>"
$PN"J5"1;
"VSS<387>"
$PN"J7"1;
"VSS<386>"
$PN"H65"1;
"VSS<385>"
$PN"J11"1;
"VSS<384>"
$PN"J15"1;
"VSS<383>"
$PN"J22"1;
"VSS<382>"
$PN"J37"1;
"VSS<381>"
$PN"J44"1;
"VSS<380>"
$PN"J59"1;
"VSS<379>"
$PN"J68"1;
"VSS<378>"
$PN"J70"1;
"VSS<377>"
$PN"K54"1;
"VSS<376>"
$PN"K69"1;
"VSS<375>"
$PN"K71"1;
"VSS<374>"
$PN"L5"1;
"VSS<373>"
$PN"L68"1;
"VSS<372>"
$PN"M2"1;
"VSS<371>"
$PN"M22"1;
"VSS<370>"
$PN"M26"1;
"VSS<369>"
$PN"M29"1;
"VSS<368>"
$PN"M33"1;
"VSS<367>"
$PN"M37"1;
"VSS<366>"
$PN"M4"1;
"VSS<365>"
$PN"M40"1;
"VSS<364>"
$PN"N42"1;
"VSS<363>"
$PN"N50"1;
"VSS<362>"
$PN"M44"1;
"VSS<361>"
$PN"M48"1;
"VSS<360>"
$PN"N13"1;
"VSS<359>"
$PN"N17"1;
"VSS<358>"
$PN"N20"1;
"VSS<357>"
$PN"N24"1;
"VSS<356>"
$PN"N27"1;
"VSS<355>"
$PN"N31"1;
%"GND"
"1","(-375,650)","0","mstr_symbols","I14";
;
VOLTAGE"0.0V"
CDS_LIB"mstr_symbols"
SIZE"1B"
BODY_TYPE"PLUMBING"
HDL_POWER"GND";
"A\NAC"1;
%"GND"
"1","(-2800,650)","0","mstr_symbols","I15";
;
VOLTAGE"0.0V"
SIZE"1B"
CDS_LIB"mstr_symbols"
BODY_TYPE"PLUMBING"
HDL_POWER"GND";
"A\NAC"2;
%"PVNN_PCH_STBY"
"1","(-6900,4400)","0","mstr_symbols","I20";
;
VOLTAGE"1.0V"
CDS_LIB"mstr_symbols"
BODY_TYPE"PLUMBING"
HDL_POWER"PVNN_PCH_STBY";
"G\NAC"3;
%"LBG_CORE_QAT_EXT_D"
"10","(-5375,2600)","0","mstr_u_proc","I21";
;
CDS_SEC"10"
LOCATION"U7C1"
PART_NUMBER"H91415-002"
MATERIAL"IC"
PACK_TYPE"BGA1"
SEC_TYPE"BGA1"
SEC"10"
CDS_LIB"mstr_u_proc"
BOM_COST"SB"
CDS_LOCATION"U7C1"
ROOM"SB";
"VCCPRIM_AVID_SENSE"
$PN"AK36"7;
"VCCPRIM_AVID_QAT_SENSE"
$PN"V37"6;
"VCCPRIM_AVID<0>"
$PN"AU36"3;
"VCCPRIM_AVID<1>"
$PN"AU34"3;
"VCCPRIM_AVID<2>"
$PN"AU32"3;
"VCCPRIM_AVID<3>"
$PN"AT36"3;
"VCCPRIM_AVID<4>"
$PN"AT34"3;
"VCCPRIM_AVID<5>"
$PN"AT32"3;
"VCCPRIM_AVID<6>"
$PN"AP39"3;
"VCCPRIM_AVID<7>"
$PN"AP37"3;
"VCCPRIM_AVID<8>"
$PN"AP36"3;
"VCCPRIM_AVID<9>"
$PN"AP34"3;
"VCCPRIM_AVID<10>"
$PN"AP32"3;
"VCCPRIM_AVID<11>"
$PN"AM39"3;
"VCCPRIM_AVID<12>"
$PN"AM37"3;
"VCCPRIM_AVID<13>"
$PN"AM36"3;
"VCCPRIM_AVID<14>"
$PN"AM34"3;
"VCCPRIM_AVID<15>"
$PN"AM32"3;
"VCCPRIM_AVID<16>"
$PN"AK39"3;
"VCCPRIM_AVID<17>"
$PN"AK37"3;
"VCCPRIM_AVID<18>"
$PN"AK34"3;
"VCCPRIM_AVID<19>"
$PN"AG39"3;
"VCCPRIM_AVID<20>"
$PN"AG37"3;
"VCCPRIM_AVID<21>"
$PN"AG36"3;
"VCCPRIM_AVID<22>"
$PN"AG34"3;
"VCCPRIM_AVID<23>"
$PN"AG32"3;
"VCCPRIM_AVID<24>"
$PN"AE41"3;
"VCCPRIM_AVID<25>"
$PN"AE39"3;
"VCCPRIM_AVID<26>"
$PN"AE37"3;
"VCCPRIM_AVID<27>"
$PN"AE36"3;
"VCCPRIM_AVID<28>"
$PN"AE34"3;
"VCCPRIM_AVID<29>"
$PN"AE32"3;
"VCCPRIM_AVID<30>"
$PN"AE30"3;
"VCCPRIM_AVID<31>"
$PN"U27"4;
"VCCPRIM_AVID<32>"
$PN"AC41"3;
"VCCPRIM_AVID<33>"
$PN"AC39"3;
"VCCPRIM_AVID<34>"
$PN"AC37"3;
"VCCPRIM_AVID<35>"
$PN"AC36"3;
"VCCPRIM_AVID<36>"
$PN"AC34"3;
"VCCPRIM_AVID<37>"
$PN"AC32"3;
"VCCPRIM_AVID<38>"
$PN"AC30"3;
"VCCPRIM_AVID<39>"
$PN"AC29"3;
"VCCPRIM_AVID<40>"
$PN"AA41"3;
"VCCPRIM_AVID<41>"
$PN"AA39"3;
"VCCPRIM_AVID<42>"
$PN"AA37"3;
"VCCPRIM_AVID<43>"
$PN"AA36"3;
"VCCPRIM_AVID<44>"
$PN"AA34"3;
"VCCPRIM_AVID<45>"
$PN"AA32"3;
"VCCPRIM_AVID<46>"
$PN"AA30"3;
"VCCPRIM_AVID<47>"
$PN"AA29"3;
"VCCPRIM_AVID<48>"
$PN"Y41"3;
"VCCPRIM_AVID<49>"
$PN"Y39"3;
"VCCPRIM_AVID<50>"
$PN"Y37"3;
"VCCPRIM_AVID<51>"
$PN"Y36"3;
"VCCPRIM_AVID<52>"
$PN"Y34"3;
"VCCPRIM_AVID<53>"
$PN"Y32"3;
"VCCPRIM_AVID<54>"
$PN"Y30"3;
"VCCPRIM_AVID<55>"
$PN"Y29"3;
"VCCPRIM_AVID<56>"
$PN"V40"3;
"VCCPRIM_AVID<57>"
$PN"V33"3;
"VCCPRIM_AVID<58>"
$PN"V29"3;
"VCCPRIM_AVID<59>"
$PN"U38"3;
"VCCPRIM_AVID<60>"
$PN"U35"3;
"VCCPRIM_AVID<61>"
$PN"U31"3;
"VCCPRIM_AVID<62>"
$PN"AK32"4;
"VCCMPHY_1P05<13>"
$PN"AE27"5;
%"PVNN_PCH_STBY"
"1","(-3850,4375)","0","mstr_symbols","I24";
;
VOLTAGE"1.0V"
CDS_LIB"mstr_symbols"
BODY_TYPE"PLUMBING"
HDL_POWER"PVNN_PCH_STBY";
"G\NAC"4;
%"P1V05_PCH_STBY"
"1","(-7425,2800)","0","mstr_symbols","I25";
;
VOLTAGE"1.05V"
CDS_LIB"mstr_symbols"
BODY_TYPE"PLUMBING"
HDL_POWER"P1V05_PCH_STBY";
"G\NAC"5;
END.
